(kicad_pcb
	(version 20260206)
	(generator "pcbnew")
	(generator_version "10.0")
	(general
		(thickness 1.6)
		(legacy_teardrops no)
	)
	(paper "A4")
	(title_block
		(title "04192023_DAF0TMB3IC0_F0TG_MB_C_brd_V02_OCP.brd")
		(comment 1 "Grand Teton / footprints 1749-1753 of 8354")
	)
	(layers
		(0 "F.Cu" signal "TOP")
		(4 "In1.Cu" signal "GND")
		(6 "In2.Cu" signal "IN1")
		(8 "In3.Cu" signal "GND1")
		(10 "In4.Cu" signal "IN2")
		(12 "In5.Cu" signal "GND2")
		(14 "In6.Cu" signal "IN3")
		(16 "In7.Cu" signal "GND3")
		(18 "In8.Cu" signal "VCC")
		(20 "In9.Cu" signal "VCC1")
		(22 "In10.Cu" signal "GND4")
		(24 "In11.Cu" signal "IN4")
		(26 "In12.Cu" signal "GND5")
		(28 "In13.Cu" signal "IN5")
		(30 "In14.Cu" signal "GND6")
		(32 "In15.Cu" signal "IN6")
		(34 "In16.Cu" signal "GND7")
		(2 "B.Cu" signal "BOTTOM")
		(9 "F.Adhes" user "F.Adhesive")
		(11 "B.Adhes" user "B.Adhesive")
		(13 "F.Paste" user "Package Geometry/Pastemask Top")
		(15 "B.Paste" user "Package Geometry/Pastemask Bottom")
		(5 "F.SilkS" user "Ref Des/Silkscreen Top")
		(7 "B.SilkS" user "Ref Des/Silkscreen Bottom")
		(1 "F.Mask" user "Board Geometry/Soldermask Top")
		(3 "B.Mask" user "Board Geometry/Soldermask Bottom")
		(17 "Dwgs.User" user "User.Drawings")
		(19 "Cmts.User" user "User.Comments")
		(21 "Eco1.User" user "User.Eco1")
		(23 "Eco2.User" user "User.Eco2")
		(25 "Edge.Cuts" user "Board Geometry/Outline")
		(27 "Margin" user)
		(31 "F.CrtYd" user "Package Geometry/Place Bound Top")
		(29 "B.CrtYd" user "Package Geometry/Place Bound Bottom")
		(35 "F.Fab" user "Ref Des/Assembly Top")
		(33 "B.Fab" user "Ref Des/Assembly Bottom")
	)
	(footprint ""
		(layer "F.Cu")
		(at 49.860454 -346.719398 -90)
		(property "Reference" "PC437_IOP1_1"
			(at 0 0 270)
			(layer "F.SilkS")
			(hide yes)
			(effects
				(font
					(size 1.27 1.27)
				)
			)
		)
		(property "Value" ""
			(at 0 0 270)
			(layer "F.Fab")
			(effects
				(font
					(size 1.27 1.27)
				)
			)
		)
		(duplicate_pad_numbers_are_jumpers no)
		(fp_line
			(start -0.7874 0.4064)
			(end -0.7874 -0.4064)
			(stroke
				(width 0.1524)
				(type default)
			)
			(layer "F.SilkS")
		)
		(fp_line
			(start 0.7874 0.4064)
			(end -0.7874 0.4064)
			(stroke
				(width 0.1524)
				(type default)
			)
			(layer "F.SilkS")
		)
		(fp_line
			(start -0.7874 -0.4064)
			(end 0.7874 -0.4064)
			(stroke
				(width 0.1524)
				(type default)
			)
			(layer "F.SilkS")
		)
		(fp_line
			(start 0.7874 -0.4064)
			(end 0.7874 0.4064)
			(stroke
				(width 0.1524)
				(type default)
			)
			(layer "F.SilkS")
		)
		(fp_line
			(start -0.67945 0.3048)
			(end -0.67945 -0.305054)
			(stroke
				(width 0.1)
				(type default)
			)
			(layer "F.Fab")
		)
		(fp_line
			(start -0.12065 0.3048)
			(end -0.67945 0.3048)
			(stroke
				(width 0.1)
				(type default)
			)
			(layer "F.Fab")
		)
		(fp_line
			(start 0.120396 0.3048)
			(end 0.120396 0.2794)
			(stroke
				(width 0.1)
				(type default)
			)
			(layer "F.Fab")
		)
		(fp_line
			(start 0.67945 0.3048)
			(end 0.120396 0.3048)
			(stroke
				(width 0.1)
				(type default)
			)
			(layer "F.Fab")
		)
		(fp_line
			(start -0.12065 0.2794)
			(end -0.12065 0.3048)
			(stroke
				(width 0.1)
				(type default)
			)
			(layer "F.Fab")
		)
		(fp_line
			(start 0.120396 0.2794)
			(end -0.12065 0.2794)
			(stroke
				(width 0.1)
				(type default)
			)
			(layer "F.Fab")
		)
		(fp_line
			(start -0.12065 -0.2794)
			(end 0.12065 -0.2794)
			(stroke
				(width 0.1)
				(type default)
			)
			(layer "F.Fab")
		)
		(fp_line
			(start 0.12065 -0.2794)
			(end 0.12065 -0.3048)
			(stroke
				(width 0.1)
				(type default)
			)
			(layer "F.Fab")
		)
		(fp_line
			(start 0.12065 -0.3048)
			(end 0.67945 -0.3048)
			(stroke
				(width 0.1)
				(type default)
			)
			(layer "F.Fab")
		)
		(fp_line
			(start 0.67945 -0.3048)
			(end 0.67945 0.3048)
			(stroke
				(width 0.1)
				(type default)
			)
			(layer "F.Fab")
		)
		(fp_line
			(start -0.67945 -0.305054)
			(end -0.12065 -0.305054)
			(stroke
				(width 0.1)
				(type default)
			)
			(layer "F.Fab")
		)
		(fp_line
			(start -0.12065 -0.305054)
			(end -0.12065 -0.2794)
			(stroke
				(width 0.1)
				(type default)
			)
			(layer "F.Fab")
		)
		(pad "1" smd circle
			(at -0.40005 0 270)
			(size 0 0)
			(layers "F.Cu" "F.Mask" "F.Paste")
			(net "PVDDCR_CPU1_P1_PVCC")
		)
		(pad "2" smd circle
			(at 0.40005 0 270)
			(size 0 0)
			(layers "F.Cu" "F.Mask" "F.Paste")
			(net "GND")
		)
	)
	(footprint ""
		(layer "F.Cu")
		(at 147.09775 -191.35471 -90)
		(property "Reference" "R3198"
			(at 0 0 270)
			(layer "F.SilkS")
			(hide yes)
			(effects
				(font
					(size 1.27 1.27)
				)
			)
		)
		(property "Value" ""
			(at 0 0 270)
			(layer "F.Fab")
			(effects
				(font
					(size 1.27 1.27)
				)
			)
		)
		(duplicate_pad_numbers_are_jumpers no)
		(fp_line
			(start -0.7874 0.4064)
			(end -0.7874 -0.01905)
			(stroke
				(width 0.1524)
				(type default)
			)
			(layer "F.SilkS")
		)
		(fp_line
			(start 0.7874 0.4064)
			(end -0.7874 0.4064)
			(stroke
				(width 0.1524)
				(type default)
			)
			(layer "F.SilkS")
		)
		(fp_line
			(start 0.7874 -0.04445)
			(end 0.7874 0.4064)
			(stroke
				(width 0.1524)
				(type default)
			)
			(layer "F.SilkS")
		)
		(fp_line
			(start -0.33909 -0.4064)
			(end 0.42291 -0.4064)
			(stroke
				(width 0.1524)
				(type default)
			)
			(layer "F.SilkS")
		)
		(fp_line
			(start -0.67945 0.3048)
			(end -0.67945 -0.305054)
			(stroke
				(width 0.1)
				(type default)
			)
			(layer "F.Fab")
		)
		(fp_line
			(start -0.12065 0.3048)
			(end -0.67945 0.3048)
			(stroke
				(width 0.1)
				(type default)
			)
			(layer "F.Fab")
		)
		(fp_line
			(start 0.120396 0.3048)
			(end 0.120396 0.2794)
			(stroke
				(width 0.1)
				(type default)
			)
			(layer "F.Fab")
		)
		(fp_line
			(start 0.67945 0.3048)
			(end 0.120396 0.3048)
			(stroke
				(width 0.1)
				(type default)
			)
			(layer "F.Fab")
		)
		(fp_line
			(start -0.12065 0.2794)
			(end -0.12065 0.3048)
			(stroke
				(width 0.1)
				(type default)
			)
			(layer "F.Fab")
		)
		(fp_line
			(start 0.120396 0.2794)
			(end -0.12065 0.2794)
			(stroke
				(width 0.1)
				(type default)
			)
			(layer "F.Fab")
		)
		(fp_line
			(start -0.12065 -0.2794)
			(end 0.12065 -0.2794)
			(stroke
				(width 0.1)
				(type default)
			)
			(layer "F.Fab")
		)
		(fp_line
			(start 0.12065 -0.2794)
			(end 0.12065 -0.3048)
			(stroke
				(width 0.1)
				(type default)
			)
			(layer "F.Fab")
		)
		(fp_line
			(start 0.12065 -0.3048)
			(end 0.67945 -0.3048)
			(stroke
				(width 0.1)
				(type default)
			)
			(layer "F.Fab")
		)
		(fp_line
			(start 0.67945 -0.3048)
			(end 0.67945 0.3048)
			(stroke
				(width 0.1)
				(type default)
			)
			(layer "F.Fab")
		)
		(fp_line
			(start -0.67945 -0.305054)
			(end -0.12065 -0.305054)
			(stroke
				(width 0.1)
				(type default)
			)
			(layer "F.Fab")
		)
		(fp_line
			(start -0.12065 -0.305054)
			(end -0.12065 -0.2794)
			(stroke
				(width 0.1)
				(type default)
			)
			(layer "F.Fab")
		)
		(pad "1" smd circle
			(at -0.40005 0 270)
			(size 0 0)
			(layers "F.Cu" "F.Mask" "F.Paste")
			(net "CLK_100M_CPU1_CLK04_R_DP")
		)
		(pad "2" smd circle
			(at 0.40005 0 270)
			(size 0 0)
			(layers "F.Cu" "F.Mask" "F.Paste")
			(net "CLK_100M_CPU1_CLK04_DP")
		)
	)
	(footprint ""
		(layer "F.Cu")
		(at 39.30396 -434.086 -90)
		(property "Reference" "R2932"
			(at 0 0 270)
			(layer "F.SilkS")
			(hide yes)
			(effects
				(font
					(size 1.27 1.27)
				)
			)
		)
		(property "Value" ""
			(at 0 0 270)
			(layer "F.Fab")
			(effects
				(font
					(size 1.27 1.27)
				)
			)
		)
		(duplicate_pad_numbers_are_jumpers no)
		(fp_line
			(start -0.7874 0.4064)
			(end -0.7874 -0.4064)
			(stroke
				(width 0.1524)
				(type default)
			)
			(layer "F.SilkS")
		)
		(fp_line
			(start 0.7874 0.4064)
			(end -0.7874 0.4064)
			(stroke
				(width 0.1524)
				(type default)
			)
			(layer "F.SilkS")
		)
		(fp_line
			(start -0.7874 -0.4064)
			(end 0.7874 -0.4064)
			(stroke
				(width 0.1524)
				(type default)
			)
			(layer "F.SilkS")
		)
		(fp_line
			(start 0.7874 -0.4064)
			(end 0.7874 0.4064)
			(stroke
				(width 0.1524)
				(type default)
			)
			(layer "F.SilkS")
		)
		(fp_line
			(start -0.67945 0.3048)
			(end -0.67945 -0.305054)
			(stroke
				(width 0.1)
				(type default)
			)
			(layer "F.Fab")
		)
		(fp_line
			(start -0.12065 0.3048)
			(end -0.67945 0.3048)
			(stroke
				(width 0.1)
				(type default)
			)
			(layer "F.Fab")
		)
		(fp_line
			(start 0.120396 0.3048)
			(end 0.120396 0.2794)
			(stroke
				(width 0.1)
				(type default)
			)
			(layer "F.Fab")
		)
		(fp_line
			(start 0.67945 0.3048)
			(end 0.120396 0.3048)
			(stroke
				(width 0.1)
				(type default)
			)
			(layer "F.Fab")
		)
		(fp_line
			(start -0.12065 0.2794)
			(end -0.12065 0.3048)
			(stroke
				(width 0.1)
				(type default)
			)
			(layer "F.Fab")
		)
		(fp_line
			(start 0.120396 0.2794)
			(end -0.12065 0.2794)
			(stroke
				(width 0.1)
				(type default)
			)
			(layer "F.Fab")
		)
		(fp_line
			(start -0.12065 -0.2794)
			(end 0.12065 -0.2794)
			(stroke
				(width 0.1)
				(type default)
			)
			(layer "F.Fab")
		)
		(fp_line
			(start 0.12065 -0.2794)
			(end 0.12065 -0.3048)
			(stroke
				(width 0.1)
				(type default)
			)
			(layer "F.Fab")
		)
		(fp_line
			(start 0.12065 -0.3048)
			(end 0.67945 -0.3048)
			(stroke
				(width 0.1)
				(type default)
			)
			(layer "F.Fab")
		)
		(fp_line
			(start 0.67945 -0.3048)
			(end 0.67945 0.3048)
			(stroke
				(width 0.1)
				(type default)
			)
			(layer "F.Fab")
		)
		(fp_line
			(start -0.67945 -0.305054)
			(end -0.12065 -0.305054)
			(stroke
				(width 0.1)
				(type default)
			)
			(layer "F.Fab")
		)
		(fp_line
			(start -0.12065 -0.305054)
			(end -0.12065 -0.2794)
			(stroke
				(width 0.1)
				(type default)
			)
			(layer "F.Fab")
		)
		(pad "1" smd circle
			(at -0.40005 0 270)
			(size 0 0)
			(layers "F.Cu" "F.Mask" "F.Paste")
			(net "FM_SWB_PWR_EN_R1_BUF")
		)
		(pad "2" smd circle
			(at 0.40005 0 270)
			(size 0 0)
			(layers "F.Cu" "F.Mask" "F.Paste")
			(net "GND")
		)
	)
	(footprint ""
		(layer "F.Cu")
		(at 240.431574 -149.965918 180)
		(property "Reference" "C1520"
			(at 0 0 180)
			(layer "F.SilkS")
			(hide yes)
			(effects
				(font
					(size 1.27 1.27)
				)
			)
		)
		(property "Value" ""
			(at 0 0 180)
			(layer "F.Fab")
			(effects
				(font
					(size 1.27 1.27)
				)
			)
		)
		(duplicate_pad_numbers_are_jumpers no)
		(fp_line
			(start 0.7874 0.4064)
			(end -0.7874 0.4064)
			(stroke
				(width 0.1524)
				(type default)
			)
			(layer "F.SilkS")
		)
		(fp_line
			(start 0.7874 -0.4064)
			(end 0.7874 0.4064)
			(stroke
				(width 0.1524)
				(type default)
			)
			(layer "F.SilkS")
		)
		(fp_line
			(start -0.7874 0.4064)
			(end -0.7874 -0.4064)
			(stroke
				(width 0.1524)
				(type default)
			)
			(layer "F.SilkS")
		)
		(fp_line
			(start -0.7874 -0.4064)
			(end 0.7874 -0.4064)
			(stroke
				(width 0.1524)
				(type default)
			)
			(layer "F.SilkS")
		)
		(fp_line
			(start 0.67945 0.3048)
			(end 0.120396 0.3048)
			(stroke
				(width 0.1)
				(type default)
			)
			(layer "F.Fab")
		)
		(fp_line
			(start 0.67945 -0.3048)
			(end 0.67945 0.3048)
			(stroke
				(width 0.1)
				(type default)
			)
			(layer "F.Fab")
		)
		(fp_line
			(start 0.12065 -0.2794)
			(end 0.12065 -0.3048)
			(stroke
				(width 0.1)
				(type default)
			)
			(layer "F.Fab")
		)
		(fp_line
			(start 0.12065 -0.3048)
			(end 0.67945 -0.3048)
			(stroke
				(width 0.1)
				(type default)
			)
			(layer "F.Fab")
		)
		(fp_line
			(start 0.120396 0.3048)
			(end 0.120396 0.2794)
			(stroke
				(width 0.1)
				(type default)
			)
			(layer "F.Fab")
		)
		(fp_line
			(start 0.120396 0.2794)
			(end -0.12065 0.2794)
			(stroke
				(width 0.1)
				(type default)
			)
			(layer "F.Fab")
		)
		(fp_line
			(start -0.12065 0.3048)
			(end -0.67945 0.3048)
			(stroke
				(width 0.1)
				(type default)
			)
			(layer "F.Fab")
		)
		(fp_line
			(start -0.12065 0.2794)
			(end -0.12065 0.3048)
			(stroke
				(width 0.1)
				(type default)
			)
			(layer "F.Fab")
		)
		(fp_line
			(start -0.12065 -0.2794)
			(end 0.12065 -0.2794)
			(stroke
				(width 0.1)
				(type default)
			)
			(layer "F.Fab")
		)
		(fp_line
			(start -0.12065 -0.305054)
			(end -0.12065 -0.2794)
			(stroke
				(width 0.1)
				(type default)
			)
			(layer "F.Fab")
		)
		(fp_line
			(start -0.67945 0.3048)
			(end -0.67945 -0.305054)
			(stroke
				(width 0.1)
				(type default)
			)
			(layer "F.Fab")
		)
		(fp_line
			(start -0.67945 -0.305054)
			(end -0.12065 -0.305054)
			(stroke
				(width 0.1)
				(type default)
			)
			(layer "F.Fab")
		)
		(pad "1" smd circle
			(at -0.40005 0 180)
			(size 0 0)
			(layers "F.Cu" "F.Mask" "F.Paste")
			(net "JTAG_CPU0_TDI")
		)
		(pad "2" smd circle
			(at 0.40005 0 180)
			(size 0 0)
			(layers "F.Cu" "F.Mask" "F.Paste")
			(net "GND")
		)
	)
	(footprint ""
		(layer "F.Cu")
		(at 366.288574 0.002794 180)
		(property "Reference" "J8067"
			(at -4.710176 -2.058416 90)
			(unlocked yes)
			(layer "F.SilkS")
			(effects
				(font
					(size 0.7874 0.5842)
					(thickness 0.1524)
				)
				(justify left)
			)
		)
		(property "Value" ""
			(at 0 0 180)
			(layer "F.Fab")
			(effects
				(font
					(size 1.27 1.27)
				)
			)
		)
		(duplicate_pad_numbers_are_jumpers no)
		(fp_line
			(start 1.2192 2.06756)
			(end -1.2192 2.06756)
			(stroke
				(width 0.1524)
				(type default)
			)
			(layer "F.SilkS")
		)
		(fp_line
			(start 1.2192 -2.06756)
			(end 1.2192 2.06756)
			(stroke
				(width 0.1524)
				(type default)
			)
			(layer "F.SilkS")
		)
		(fp_line
			(start -1.2192 2.06756)
			(end -1.2192 -2.06756)
			(stroke
				(width 0.1524)
				(type default)
			)
			(layer "F.SilkS")
		)
		(fp_line
			(start -1.2192 -2.06756)
			(end 1.2192 -2.06756)
			(stroke
				(width 0.1524)
				(type default)
			)
			(layer "F.SilkS")
		)
		(pad "" np_thru_hole circle
			(at -2.8829 -1.27 90)
			(size 1.0414 1.0414)
			(drill 1.0414)
			(layers "*.Cu" "*.Mask")
			(clearance 0.381)
			(thermal_gap 0.381)
		)
		(pad "" np_thru_hole circle
			(at -2.8829 1.27 90)
			(size 1.0414 1.0414)
			(drill 1.0414)
			(layers "*.Cu" "*.Mask")
			(clearance 0.381)
			(thermal_gap 0.381)
		)
		(pad "" np_thru_hole circle
			(at 3.4671 -1.27 90)
			(size 1.0414 1.0414)
			(drill 1.0414)
			(layers "*.Cu" "*.Mask")
			(clearance 0.381)
			(thermal_gap 0.381)
		)
		(pad "" np_thru_hole circle
			(at 3.4671 1.27 90)
			(size 1.0414 1.0414)
			(drill 1.0414)
			(layers "*.Cu" "*.Mask")
			(clearance 0.381)
			(thermal_gap 0.381)
		)
		(pad "1" smd rect
			(at 0.8255 -0.249936 90)
			(size 0.3048 0.508)
			(layers "F.Cu" "F.Mask" "F.Paste")
			(net "DELTA_L_85_5INCH_IN3_DP")
		)
		(pad "2" smd rect
			(at 0.8255 0.249936 90)
			(size 0.3048 0.508)
			(layers "F.Cu" "F.Mask" "F.Paste")
			(net "DELTA_L_85_5INCH_IN3_DN")
		)
		(pad "3" smd circle
			(at 0 0 180)
			(size 0 0)
			(layers "F.Cu" "F.Mask" "F.Paste")
			(net "DELTA_L_GND_1")
		)
		(zone
			(layer "F.Cu")
			(hatch none 0.5)
			(connect_pads
				(clearance 0)
			)
			(min_thickness 0.25)
			(keepout
				(tracks not_allowed)
				(vias allowed)
				(pads allowed)
				(copperpour not_allowed)
				(footprints allowed)
			)
			(placement
				(enabled no)
				(sheetname "")
			)
			(fill
				(thermal_gap 0.5)
				(thermal_bridge_width 0.5)
				(island_removal_mode 0)
			)
			(polygon
				(pts
					(xy 365.170974 0.551434) (xy 365.170974 0.45593) (xy 365.767874 0.45593) (xy 365.767874 0.04953)
					(xy 365.170974 0.04953) (xy 365.170974 -0.043942) (xy 365.767874 -0.043942) (xy 365.767874 -0.450342)
					(xy 365.170974 -0.450342) (xy 365.170974 -0.545846) (xy 365.869474 -0.545846) (xy 365.869474 0.551434)
				)
			)
		)
		(zone
			(layers "F.Cu" "B.Cu" "In1.Cu" "In2.Cu" "In3.Cu" "In4.Cu" "In5.Cu" "In6.Cu"
				"In7.Cu" "In8.Cu" "In9.Cu" "In10.Cu" "In11.Cu" "In12.Cu" "In13.Cu" "In14.Cu"
				"In15.Cu" "In16.Cu"
			)
			(hatch none 0.5)
			(connect_pads
				(clearance 0)
			)
			(min_thickness 0.25)
			(keepout
				(tracks not_allowed)
				(vias allowed)
				(pads allowed)
				(copperpour not_allowed)
				(footprints allowed)
			)
			(placement
				(enabled no)
				(sheetname "")
			)
			(fill
				(thermal_gap 0.5)
				(thermal_bridge_width 0.5)
				(island_removal_mode 0)
			)
			(polygon
				(pts
					(arc
						(start 363.748574 -1.267206)
						(mid 361.894374 -1.267206)
						(end 363.748574 -1.267206)
					)
				)
			)
		)
		(zone
			(layers "F.Cu" "B.Cu" "In1.Cu" "In2.Cu" "In3.Cu" "In4.Cu" "In5.Cu" "In6.Cu"
				"In7.Cu" "In8.Cu" "In9.Cu" "In10.Cu" "In11.Cu" "In12.Cu" "In13.Cu" "In14.Cu"
				"In15.Cu" "In16.Cu"
			)
			(hatch none 0.5)
			(connect_pads
				(clearance 0)
			)
			(min_thickness 0.25)
			(keepout
				(tracks not_allowed)
				(vias allowed)
				(pads allowed)
				(copperpour not_allowed)
				(footprints allowed)
			)
			(placement
				(enabled no)
				(sheetname "")
			)
			(fill
				(thermal_gap 0.5)
				(thermal_bridge_width 0.5)
				(island_removal_mode 0)
			)
			(polygon
				(pts
					(arc
						(start 363.748574 1.272794)
						(mid 361.894374 1.272794)
						(end 363.748574 1.272794)
					)
				)
			)
		)
		(zone
			(layers "F.Cu" "B.Cu" "In1.Cu" "In2.Cu" "In3.Cu" "In4.Cu" "In5.Cu" "In6.Cu"
				"In7.Cu" "In8.Cu" "In9.Cu" "In10.Cu" "In11.Cu" "In12.Cu" "In13.Cu" "In14.Cu"
				"In15.Cu" "In16.Cu"
			)
			(hatch none 0.5)
			(connect_pads
				(clearance 0)
			)
			(min_thickness 0.25)
			(keepout
				(tracks not_allowed)
				(vias allowed)
				(pads allowed)
				(copperpour not_allowed)
				(footprints allowed)
			)
			(placement
				(enabled no)
				(sheetname "")
			)
			(fill
				(thermal_gap 0.5)
				(thermal_bridge_width 0.5)
				(island_removal_mode 0)
			)
			(polygon
				(pts
					(arc
						(start 370.098574 -1.267206)
						(mid 368.244374 -1.267206)
						(end 370.098574 -1.267206)
					)
				)
			)
		)
		(zone
			(layers "F.Cu" "B.Cu" "In1.Cu" "In2.Cu" "In3.Cu" "In4.Cu" "In5.Cu" "In6.Cu"
				"In7.Cu" "In8.Cu" "In9.Cu" "In10.Cu" "In11.Cu" "In12.Cu" "In13.Cu" "In14.Cu"
				"In15.Cu" "In16.Cu"
			)
			(hatch none 0.5)
			(connect_pads
				(clearance 0)
			)
			(min_thickness 0.25)
			(keepout
				(tracks not_allowed)
				(vias allowed)
				(pads allowed)
				(copperpour not_allowed)
				(footprints allowed)
			)
			(placement
				(enabled no)
				(sheetname "")
			)
			(fill
				(thermal_gap 0.5)
				(thermal_bridge_width 0.5)
				(island_removal_mode 0)
			)
			(polygon
				(pts
					(arc
						(start 370.098574 1.272794)
						(mid 368.244374 1.272794)
						(end 370.098574 1.272794)
					)
				)
			)
		)
	)
)
